FILE_TYPE = MULTI_PHYS_TABLE;
PART 'ICS9FGP204'
{========================================================================================}
: PACK_TYPE   | MATERIAL   | PART_NUMBER    = EnvComp | PART_NUMBER   | JEDEC_TYPE      | DESCRIPTION                                  | CLASS   | HEIGHT     | COMPONENT_TYPE   | LPID  | SPEED_URL | Status |RPL| AML | Bus_Unit | Days ;
{========================================================================================}
'MLFP'       |'IC'        |'E95226-001' (!)  = 'YES;YES;YES;UNK;ok;VLD' |'E95226-001'   |'MLFP40_6_50MA'  |'FREQUENCY TIMING GENERATOR FOR PERIPHERALS'  |'IC'     |'0.039 IN'  |'LCC'             |'751' | 'http://speed.intel.com:8081/speed/module/pdm/item/pdm_item_detail_direct.asp?item_cde=E95226-001&item_rev=01&url_param=unused' | 'Conditional' | 'YES' | '2' | 'SMO_IC' | '84' 
'MLFP'       |'EMPTY'     |'E95226-001' (!)  = 'YES;YES;YES;UNK;ok;VLD' |'E95226-001'   |'MLFP40_6_50MA'  |'FREQUENCY TIMING GENERATOR FOR PERIPHERALS'  |'IO'     |'0.039 IN'  |'LCC'             |'751' | 'http://speed.intel.com:8081/speed/module/pdm/item/pdm_item_detail_direct.asp?item_cde=E95226-001&item_rev=01&url_param=unused' | 'Conditional' | 'YES' | '2' | 'SMO_IC' | '84' 
END_PART
END.
